#ISCELL
  mstr_misc dns *
  *
#ISCELL
  pure_quanta quanta_title_block_c *
  *
#CELL
  pure_quanta pca9306dp1 *
  page183_i27
#CELL
  pure_quanta q_cap *
  page183_i28
#ISCELL
  logical_power universal_power *
  page183_i29
#ISCELL
  logical_power universal_power *
  page183_i3
#ISCELL
  logical_power universal_gnd *
  page183_i30
#ISCELL
  logical_power universal_gnd *
  page183_i38
#CELL
  pure_quanta q_res *
  page183_i43
#CELL
  pure_quanta q_res *
  page183_i45
#ISCELL
  logical_power universal_power *
  page183_i47
#CELL
  pure_quanta q_res *
  page183_i5
#ISCELL
  logical_power universal_power *
  page183_i51
#CELL
  pure_quanta q_cap *
  page183_i52
#ISCELL
  logical_power universal_gnd *
  page183_i53
#ISCELL
  standard offpage *
  page183_i54
#ISCELL
  standard offpage *
  page183_i55
#CELL
  pure_quanta q_res *
  page183_i65
#CELL
  pure_quanta q_res *
  page183_i66
#ISCELL
  standard offpage *
  page183_i67
#ISCELL
  standard offpage *
  page183_i68
#ISCELL
  standard offpage *
  page183_i7
#CELL
  pure_quanta q_res *
  page183_i70
#ISCELL
  standard offpage *
  page183_i71
#CELL
  pure_quanta q_res *
  page183_i72
#ISCELL
  standard offpage *
  page183_i73
#ISCELL
  standard offpage *
  page183_i74
#CELL
  pure_quanta q_res *
  page183_i76
#CELL
  pure_quanta q_res *
  page183_i77
#CELL
  pure_quanta q_res *
  page183_i78
#CELL
  pure_quanta q_res *
  page183_i80
#CELL
  pure_quanta q_cap *
  page183_i82
#ISCELL
  logical_power universal_gnd *
  page183_i84
#ISCELL
  logical_power universal_power *
  page183_i87
#CELL
  pure_quanta q_cap *
  page183_i89
#ISCELL
  logical_power universal_gnd *
  page183_i90
#ISCELL
  standard offpage *
  page183_i91
#ISCELL
  standard offpage *
  page183_i92
#CELL
  pure_quanta pca9617adp *
  page183_i93
#ISCELL
  standard offpage *
  page183_i94
#ISCELL
  logical_power universal_gnd *
  page183_i95
#CELL
  pure_quanta q_res *
  page183_i96
#ISCELL
  logical_power universal_power *
  page183_i97
#ISCELL
  logical_power universal_power *
  page183_i98
#CELL
  pure_quanta q_res *
  page183_i99
